FILE_TYPE = MULTI_PHYS_TABLE;

PART 'TS3A5018PWR_TSSOP16'
CLASS = IC

{========================================================================================}
:CLS_PN             = JEDEC_TYPE       |ALT_SYMBOLS          |DESCRIPTION    ;
{========================================================================================}
 'G220-10324-01'   = 'SOP16_173_P0256'  |'(SOP16_173_P0256)'  |'IC,TS3A5018,ANALOG SWITCH,QUAD SPDT,TSSOP16'  

END_PART

END.

